(kicad_pcb
	(version 20260206)
	(generator "pcbnew")
	(generator_version "10.0")
	(general
		(thickness 1.6)
		(legacy_teardrops no)
	)
	(paper "A4")
	(title_block
		(title "Bryce Canyon_R.DPB_16317-1_OCP.brd")
		(comment 1 "Bryce Canyon / footprints 927-932 of 2099")
	)
	(layers
		(0 "F.Cu" signal "TOP")
		(4 "In1.Cu" signal "L2GND")
		(6 "In2.Cu" signal "L3")
		(8 "In3.Cu" signal "L4VCC")
		(10 "In4.Cu" signal "L5VCC")
		(12 "In5.Cu" signal "L6")
		(14 "In6.Cu" signal "L7GND")
		(2 "B.Cu" signal "BOTTOM")
		(9 "F.Adhes" user "F.Adhesive")
		(11 "B.Adhes" user "B.Adhesive")
		(13 "F.Paste" user "Package Geometry/Pastemask Top")
		(15 "B.Paste" user "Package Geometry/Pastemask Bottom")
		(5 "F.SilkS" user "Ref Des/Silkscreen Top")
		(7 "B.SilkS" user "Ref Des/Silkscreen Bottom")
		(1 "F.Mask" user "Board Geometry/Soldermask Top")
		(3 "B.Mask" user "Board Geometry/Soldermask Bottom")
		(17 "Dwgs.User" user "User.Drawings")
		(19 "Cmts.User" user "User.Comments")
		(21 "Eco1.User" user "User.Eco1")
		(23 "Eco2.User" user "User.Eco2")
		(25 "Edge.Cuts" user "Board Geometry/Outline")
		(27 "Margin" user)
		(31 "F.CrtYd" user "Package Geometry/Place Bound Top")
		(29 "B.CrtYd" user "Package Geometry/Place Bound Bottom")
		(35 "F.Fab" user "Ref Des/Assembly Top")
		(33 "B.Fab" user "Ref Des/Assembly Bottom")
	)
	(footprint ""
		(layer "F.Cu")
		(at 141.097 -30.861)
		(property "Reference" "Q144"
			(at 0 0 0)
			(layer "F.SilkS")
			(hide yes)
			(effects
				(font
					(size 1.27 1.27)
				)
			)
		)
		(property "Value" "AO4407AL-GP"
			(at -3.707384 -1.5367 0)
			(unlocked yes)
			(layer "F.Fab")
			(hide yes)
			(effects
				(font
					(size 1.016 1.016)
					(thickness 0.1524)
				)
			)
		)
		(property "Device Type" "SOIC8H69"
			(at -3.707384 -3.0607 0)
			(unlocked yes)
			(layer "F.Fab")
			(hide yes)
			(effects
				(font
					(size 1.016 1.016)
					(thickness 0.1524)
				)
			)
		)
		(duplicate_pad_numbers_are_jumpers no)
		(fp_line
			(start -2.7432 -1.4224)
			(end -2.7432 1.4224)
			(stroke
				(width 0.1524)
				(type default)
			)
			(layer "F.SilkS")
		)
		(fp_line
			(start -2.7432 1.4224)
			(end -2.6416 1.4224)
			(stroke
				(width 0.1524)
				(type default)
			)
			(layer "F.SilkS")
		)
		(fp_line
			(start -2.7432 1.4224)
			(end 2.1336 1.4224)
			(stroke
				(width 0.1524)
				(type default)
			)
			(layer "F.SilkS")
		)
		(fp_line
			(start -2.7178 -0.508)
			(end -2.1844 -0.0508)
			(stroke
				(width 0.1524)
				(type default)
			)
			(layer "F.SilkS")
		)
		(fp_line
			(start -2.6289 3.4417)
			(end -2.6289 1.4732)
			(stroke
				(width 0.381)
				(type default)
			)
			(layer "F.SilkS")
		)
		(fp_line
			(start -2.1844 -0.0508)
			(end -2.7178 0.508)
			(stroke
				(width 0.1524)
				(type default)
			)
			(layer "F.SilkS")
		)
		(fp_line
			(start 2.1336 -1.4224)
			(end -2.7432 -1.4224)
			(stroke
				(width 0.1524)
				(type default)
			)
			(layer "F.SilkS")
		)
		(fp_line
			(start 2.1336 1.4224)
			(end 2.1336 -1.4224)
			(stroke
				(width 0.1524)
				(type default)
			)
			(layer "F.SilkS")
		)
		(fp_poly
			(pts
				(xy -2.2098 -1.4224) (xy -2.2098 1.4224) (xy 2.2098 1.4224) (xy 2.2098 -1.4224)
			)
			(stroke
				(width 0)
				(type default)
			)
			(fill yes)
			(layer "F.SilkS")
		)
		(fp_rect
			(start -2.450084 2.999994)
			(end 2.450084 -2.999994)
			(stroke
				(width 0)
				(type default)
			)
			(fill no)
			(layer "F.CrtYd")
		)
		(fp_poly
			(pts
				(xy -2.8194 3.6322) (xy -2.8194 -3.6322) (xy 2.8194 -3.6322) (xy 2.8194 1.18364) (xy 2.450084 1.18364)
				(xy 2.450084 -2.999994) (xy -2.450084 -2.999994) (xy -2.450084 2.999994) (xy 2.450084 2.999994)
				(xy 2.450084 1.18618) (xy 2.8194 1.18618) (xy 2.8194 3.6322)
			)
			(stroke
				(width 0)
				(type default)
			)
			(fill no)
			(layer "F.CrtYd")
		)
		(fp_rect
			(start -2.8194 3.6322)
			(end 2.8194 -3.6322)
			(stroke
				(width 0)
				(type default)
			)
			(fill no)
			(layer "F.Fab")
		)
		(pad "1" smd rect
			(at -1.905 2.54)
			(size 0.635 1.651)
			(layers "F.Cu" "F.Mask" "F.Paste")
			(net "P12V_B")
		)
		(pad "2" smd rect
			(at -0.635 2.54)
			(size 0.635 1.651)
			(layers "F.Cu" "F.Mask" "F.Paste")
			(net "P12V_B")
		)
		(pad "3" smd rect
			(at 0.635 2.54)
			(size 0.635 1.651)
			(layers "F.Cu" "F.Mask" "F.Paste")
			(net "P12V_B")
		)
		(pad "4" smd rect
			(at 1.905 2.54)
			(size 0.635 1.651)
			(layers "F.Cu" "F.Mask" "F.Paste")
			(net "SW_HDD_N28")
		)
		(pad "5" smd rect
			(at 1.905 -2.54)
			(size 0.635 1.651)
			(layers "F.Cu" "F.Mask" "F.Paste")
			(net "P12V_HDD28")
		)
		(pad "6" smd rect
			(at 0.635 -2.54)
			(size 0.635 1.651)
			(layers "F.Cu" "F.Mask" "F.Paste")
			(net "P12V_HDD28")
		)
		(pad "7" smd rect
			(at -0.635 -2.54)
			(size 0.635 1.651)
			(layers "F.Cu" "F.Mask" "F.Paste")
			(net "P12V_HDD28")
		)
		(pad "8" smd rect
			(at -1.905 -2.54)
			(size 0.635 1.651)
			(layers "F.Cu" "F.Mask" "F.Paste")
			(net "P12V_HDD28")
		)
	)
	(footprint ""
		(layer "F.Cu")
		(at 230.378 -193.7004)
		(property "Reference" "Q29"
			(at 0 0 0)
			(layer "F.SilkS")
			(hide yes)
			(effects
				(font
					(size 1.27 1.27)
				)
			)
		)
		(property "Value" "SSM3K324R-GP"
			(at 0.127 -8.9662 0)
			(unlocked yes)
			(layer "F.Fab")
			(hide yes)
			(effects
				(font
					(size 1.016 1.016)
					(thickness 0.1524)
				)
			)
		)
		(property "Device Type" "SOT23DGS2D4H35"
			(at 0.127 -10.4902 0)
			(unlocked yes)
			(layer "F.Fab")
			(hide yes)
			(effects
				(font
					(size 1.016 1.016)
					(thickness 0.1524)
				)
			)
		)
		(duplicate_pad_numbers_are_jumpers no)
		(fp_line
			(start -1.651 -1.778)
			(end -1.651 1.778)
			(stroke
				(width 0.1524)
				(type default)
			)
			(layer "F.SilkS")
		)
		(fp_line
			(start -1.651 1.778)
			(end 1.651 1.778)
			(stroke
				(width 0.1524)
				(type default)
			)
			(layer "F.SilkS")
		)
		(fp_line
			(start 1.651 -1.778)
			(end -1.651 -1.778)
			(stroke
				(width 0.1524)
				(type default)
			)
			(layer "F.SilkS")
		)
		(fp_line
			(start 1.651 1.778)
			(end 1.651 -1.778)
			(stroke
				(width 0.1524)
				(type default)
			)
			(layer "F.SilkS")
		)
		(fp_poly
			(pts
				(xy -1.778 1.8796) (xy -1.778 -1.8796) (xy 1.778 -1.8796) (xy 1.778 1.8796)
			)
			(stroke
				(width 0)
				(type default)
			)
			(fill no)
			(layer "F.CrtYd")
		)
		(fp_poly
			(pts
				(xy -1.778 1.8796) (xy -1.778 -1.8796) (xy 1.778 -1.8796) (xy 1.778 1.8796)
			)
			(stroke
				(width 0)
				(type default)
			)
			(fill no)
			(layer "F.Fab")
		)
		(pad "D" smd custom
			(at 0 -0.9525)
			(size 0.1905 0.1905)
			(layers "F.Cu" "F.Mask" "F.Paste")
			(net "P3V3_STBY_B")
			(options
				(clearance outline)
				(anchor circle)
			)
			(primitives
				(gr_poly
					(pts
						(arc
							(start -0.1778 0.5715)
							(mid -0.321484 0.511984)
							(end -0.381 0.3683)
						)
						(arc
							(start -0.381 -0.3683)
							(mid -0.321484 -0.511984)
							(end -0.1778 -0.5715)
						)
						(arc
							(start 0.1778 -0.5715)
							(mid 0.321484 -0.511984)
							(end 0.381 -0.3683)
						)
						(arc
							(start 0.381 0.3683)
							(mid 0.321484 0.511984)
							(end 0.1778 0.5715)
						)
					)
					(width 0)
					(fill yes)
				)
			)
		)
		(pad "G" smd custom
			(at -0.98425 0.9525)
			(size 0.1905 0.1905)
			(layers "F.Cu" "F.Mask" "F.Paste")
			(net "SCC_FULL_PWR_EN_5V")
			(options
				(clearance outline)
				(anchor circle)
			)
			(primitives
				(gr_poly
					(pts
						(arc
							(start -0.1778 0.5715)
							(mid -0.321484 0.511984)
							(end -0.381 0.3683)
						)
						(arc
							(start -0.381 -0.3683)
							(mid -0.321484 -0.511984)
							(end -0.1778 -0.5715)
						)
						(arc
							(start 0.1778 -0.5715)
							(mid 0.321484 -0.511984)
							(end 0.381 -0.3683)
						)
						(arc
							(start 0.381 0.3683)
							(mid 0.321484 0.511984)
							(end 0.1778 0.5715)
						)
					)
					(width 0)
					(fill yes)
				)
			)
		)
		(pad "S" smd custom
			(at 0.98425 0.9525)
			(size 0.1905 0.1905)
			(layers "F.Cu" "F.Mask" "F.Paste")
			(net "GPIO_VCC_U9")
			(options
				(clearance outline)
				(anchor circle)
			)
			(primitives
				(gr_poly
					(pts
						(arc
							(start -0.1778 0.5715)
							(mid -0.321484 0.511984)
							(end -0.381 0.3683)
						)
						(arc
							(start -0.381 -0.3683)
							(mid -0.321484 -0.511984)
							(end -0.1778 -0.5715)
						)
						(arc
							(start 0.1778 -0.5715)
							(mid 0.321484 -0.511984)
							(end 0.381 -0.3683)
						)
						(arc
							(start 0.381 0.3683)
							(mid 0.321484 0.511984)
							(end 0.1778 0.5715)
						)
					)
					(width 0)
					(fill yes)
				)
			)
		)
	)
	(footprint ""
		(layer "F.Cu")
		(at 20.210018 -99.401884)
		(property "Reference" "R382"
			(at 0 0 0)
			(layer "F.SilkS")
			(hide yes)
			(effects
				(font
					(size 1.27 1.27)
				)
			)
		)
		(property "Value" "130R3F-GP"
			(at -0.0254 -2.5146 0)
			(unlocked yes)
			(layer "F.Fab")
			(hide yes)
			(effects
				(font
					(size 1.016 1.016)
					(thickness 0.1524)
				)
			)
		)
		(property "Device Type" "R603H22"
			(at -0.0254 -4.0386 0)
			(unlocked yes)
			(layer "F.Fab")
			(hide yes)
			(effects
				(font
					(size 1.016 1.016)
					(thickness 0.1524)
				)
			)
		)
		(duplicate_pad_numbers_are_jumpers no)
		(fp_line
			(start -0.4826 0)
			(end -0.2032 0)
			(stroke
				(width 0.2032)
				(type default)
			)
			(layer "F.SilkS")
		)
		(fp_line
			(start 0.2032 0)
			(end 0.4826 0)
			(stroke
				(width 0.2032)
				(type default)
			)
			(layer "F.SilkS")
		)
		(fp_rect
			(start -0.5842 1.3335)
			(end 0.5842 -1.3335)
			(stroke
				(width 0)
				(type default)
			)
			(fill no)
			(layer "F.CrtYd")
		)
		(fp_rect
			(start -0.5842 1.3335)
			(end 0.5842 -1.3335)
			(stroke
				(width 0)
				(type default)
			)
			(fill no)
			(layer "F.Fab")
		)
		(pad "1" smd custom
			(at 0 -0.762)
			(size 0.2159 0.2159)
			(layers "F.Cu" "F.Mask" "F.Paste")
			(net "P5V_B_1")
			(options
				(clearance outline)
				(anchor circle)
			)
			(primitives
				(gr_poly
					(pts
						(arc
							(start -0.3302 -0.4318)
							(mid -0.402042 -0.402042)
							(end -0.4318 -0.3302)
						)
						(arc
							(start -0.4318 0.3302)
							(mid -0.402042 0.402042)
							(end -0.3302 0.4318)
						)
						(arc
							(start 0.3302 0.4318)
							(mid 0.402042 0.402042)
							(end 0.4318 0.3302)
						)
						(arc
							(start 0.4318 -0.3302)
							(mid 0.402042 -0.402042)
							(end 0.3302 -0.4318)
						)
					)
					(width 0)
					(fill yes)
				)
			)
		)
		(pad "2" smd custom
			(at 0 0.762)
			(size 0.2159 0.2159)
			(layers "F.Cu" "F.Mask" "F.Paste")
			(net "FLT_HDD12")
			(options
				(clearance outline)
				(anchor circle)
			)
			(primitives
				(gr_poly
					(pts
						(arc
							(start -0.3302 -0.4318)
							(mid -0.402042 -0.402042)
							(end -0.4318 -0.3302)
						)
						(arc
							(start -0.4318 0.3302)
							(mid -0.402042 0.402042)
							(end -0.3302 0.4318)
						)
						(arc
							(start 0.3302 0.4318)
							(mid 0.402042 0.402042)
							(end 0.4318 0.3302)
						)
						(arc
							(start 0.4318 -0.3302)
							(mid 0.402042 -0.402042)
							(end 0.3302 -0.4318)
						)
					)
					(width 0)
					(fill yes)
				)
			)
		)
	)
	(footprint ""
		(layer "F.Cu")
		(at 24.257 -160.401 180)
		(property "Reference" "C193"
			(at 0 0 180)
			(layer "F.SilkS")
			(hide yes)
			(effects
				(font
					(size 1.27 1.27)
				)
			)
		)
		(property "Value" "SC1U25V3KX-GP"
			(at 0 -2.8194 180)
			(unlocked yes)
			(layer "F.Fab")
			(hide yes)
			(effects
				(font
					(size 1.016 1.016)
					(thickness 0.1524)
				)
			)
		)
		(property "Device Type" "C603H36"
			(at 0 -4.3434 180)
			(unlocked yes)
			(layer "F.Fab")
			(hide yes)
			(effects
				(font
					(size 1.016 1.016)
					(thickness 0.1524)
				)
			)
		)
		(duplicate_pad_numbers_are_jumpers no)
		(fp_line
			(start 0.508 0)
			(end -0.508 0)
			(stroke
				(width 0.2032)
				(type default)
			)
			(layer "F.SilkS")
		)
		(fp_rect
			(start -0.5842 1.3335)
			(end 0.5842 -1.3335)
			(stroke
				(width 0)
				(type default)
			)
			(fill no)
			(layer "F.CrtYd")
		)
		(fp_rect
			(start -0.5842 1.3335)
			(end 0.5842 -1.3335)
			(stroke
				(width 0)
				(type default)
			)
			(fill no)
			(layer "F.Fab")
		)
		(pad "1" smd custom
			(at 0 -0.762 180)
			(size 0.2159 0.2159)
			(layers "F.Cu" "F.Mask" "F.Paste")
			(net "P12V_HDD12")
			(options
				(clearance outline)
				(anchor circle)
			)
			(primitives
				(gr_poly
					(pts
						(arc
							(start -0.3302 -0.4318)
							(mid -0.402042 -0.402042)
							(end -0.4318 -0.3302)
						)
						(arc
							(start -0.4318 0.3302)
							(mid -0.402042 0.402042)
							(end -0.3302 0.4318)
						)
						(arc
							(start 0.3302 0.4318)
							(mid 0.402042 0.402042)
							(end 0.4318 0.3302)
						)
						(arc
							(start 0.4318 -0.3302)
							(mid 0.402042 -0.402042)
							(end 0.3302 -0.4318)
						)
					)
					(width 0)
					(fill yes)
				)
			)
		)
		(pad "2" smd custom
			(at 0 0.762 180)
			(size 0.2159 0.2159)
			(layers "F.Cu" "F.Mask" "F.Paste")
			(net "GND")
			(options
				(clearance outline)
				(anchor circle)
			)
			(primitives
				(gr_poly
					(pts
						(arc
							(start -0.3302 -0.4318)
							(mid -0.402042 -0.402042)
							(end -0.4318 -0.3302)
						)
						(arc
							(start -0.4318 0.3302)
							(mid -0.402042 0.402042)
							(end -0.3302 0.4318)
						)
						(arc
							(start 0.3302 0.4318)
							(mid 0.402042 0.402042)
							(end 0.4318 0.3302)
						)
						(arc
							(start 0.4318 -0.3302)
							(mid 0.402042 -0.402042)
							(end 0.3302 -0.4318)
						)
					)
					(width 0)
					(fill yes)
				)
			)
		)
	)
	(footprint ""
		(layer "F.Cu")
		(at 145.161 -150.622 90)
		(property "Reference" "R439"
			(at 0 0 90)
			(layer "F.SilkS")
			(hide yes)
			(effects
				(font
					(size 1.27 1.27)
				)
			)
		)
		(property "Value" "2R6F-GP"
			(at -0.0508 -4.8514 90)
			(unlocked yes)
			(layer "F.Fab")
			(hide yes)
			(effects
				(font
					(size 1.016 1.016)
					(thickness 0.1524)
				)
			)
		)
		(property "Device Type" "R1206H26"
			(at 0 -6.3754 90)
			(unlocked yes)
			(layer "F.Fab")
			(hide yes)
			(effects
				(font
					(size 1.016 1.016)
					(thickness 0.1524)
				)
			)
		)
		(duplicate_pad_numbers_are_jumpers no)
		(fp_line
			(start 1.016 -2.2352)
			(end 1.016 2.2352)
			(stroke
				(width 0.1524)
				(type default)
			)
			(layer "F.SilkS")
		)
		(fp_line
			(start -1.016 -2.2352)
			(end 1.016 -2.2352)
			(stroke
				(width 0.1524)
				(type default)
			)
			(layer "F.SilkS")
		)
		(fp_line
			(start 1.016 2.2352)
			(end -1.016 2.2352)
			(stroke
				(width 0.1524)
				(type default)
			)
			(layer "F.SilkS")
		)
		(fp_line
			(start -1.016 2.2352)
			(end -1.016 -2.2352)
			(stroke
				(width 0.1524)
				(type default)
			)
			(layer "F.SilkS")
		)
		(fp_rect
			(start -1.0922 2.3114)
			(end 1.0922 -2.3114)
			(stroke
				(width 0)
				(type default)
			)
			(fill no)
			(layer "F.CrtYd")
		)
		(fp_poly
			(pts
				(xy -1.0922 -2.3114) (xy 1.0922 -2.3114) (xy 1.0922 2.3114) (xy -1.0922 2.3114)
			)
			(stroke
				(width 0)
				(type default)
			)
			(fill no)
			(layer "F.Fab")
		)
		(pad "1" smd rect
			(at 0 -1.397 90)
			(size 1.651 1.27)
			(layers "F.Cu" "F.Mask" "F.Paste")
			(net "P12V_HDD16")
		)
		(pad "2" smd rect
			(at 0 1.397 90)
			(size 1.651 1.27)
			(layers "F.Cu" "F.Mask" "F.Paste")
			(net "12V_PRE_16")
		)
	)
	(footprint ""
		(layer "F.Cu")
		(at 256.779522 -360.400346)
		(property "Reference" "R1029"
			(at 0 0 0)
			(layer "F.SilkS")
			(hide yes)
			(effects
				(font
					(size 1.27 1.27)
				)
			)
		)
		(property "Value" "0R2J-2-GP"
			(at 0.064008 -3.993896 0)
			(unlocked yes)
			(layer "F.Fab")
			(hide yes)
			(effects
				(font
					(size 1.016 1.016)
					(thickness 0.1524)
				)
			)
		)
		(property "Device Type" "R402H16"
			(at 0.064008 -5.517896 0)
			(unlocked yes)
			(layer "F.Fab")
			(hide yes)
			(effects
				(font
					(size 1.016 1.016)
					(thickness 0.1524)
				)
			)
		)
		(duplicate_pad_numbers_are_jumpers no)
		(fp_line
			(start -0.508 -0.9398)
			(end -0.508 0.9398)
			(stroke
				(width 0.1524)
				(type default)
			)
			(layer "F.SilkS")
		)
		(fp_line
			(start 0.508 -0.9398)
			(end -0.508 -0.9398)
			(stroke
				(width 0.1524)
				(type default)
			)
			(layer "F.SilkS")
		)
		(fp_rect
			(start -0.508 0.9398)
			(end 0.508 -0.9398)
			(stroke
				(width 0)
				(type default)
			)
			(fill no)
			(layer "F.CrtYd")
		)
		(fp_rect
			(start -0.508 0.9398)
			(end 0.508 -0.9398)
			(stroke
				(width 0)
				(type default)
			)
			(fill no)
			(layer "F.Fab")
		)
		(pad "1" smd custom
			(at 0 -0.4445)
			(size 0.1397 0.1397)
			(layers "F.Cu" "F.Mask" "F.Paste")
			(net "MB3_CM_ADR1_R")
			(options
				(clearance outline)
				(anchor circle)
			)
			(primitives
				(gr_poly
					(pts
						(arc
							(start -0.1778 -0.2794)
							(mid -0.249642 -0.249642)
							(end -0.2794 -0.1778)
						)
						(arc
							(start -0.2794 0.1778)
							(mid -0.249642 0.249642)
							(end -0.1778 0.2794)
						)
						(arc
							(start 0.1778 0.2794)
							(mid 0.249642 0.249642)
							(end 0.2794 0.1778)
						)
						(arc
							(start 0.2794 -0.1778)
							(mid 0.249642 -0.249642)
							(end 0.1778 -0.2794)
						)
					)
					(width 0)
					(fill yes)
				)
			)
		)
		(pad "2" smd custom
			(at 0 0.4445)
			(size 0.1397 0.1397)
			(layers "F.Cu" "F.Mask" "F.Paste")
			(net "AGND_CURRENT_DPB")
			(options
				(clearance outline)
				(anchor circle)
			)
			(primitives
				(gr_poly
					(pts
						(arc
							(start -0.1778 -0.2794)
							(mid -0.249642 -0.249642)
							(end -0.2794 -0.1778)
						)
						(arc
							(start -0.2794 0.1778)
							(mid -0.249642 0.249642)
							(end -0.1778 0.2794)
						)
						(arc
							(start 0.1778 0.2794)
							(mid 0.249642 0.249642)
							(end 0.2794 0.1778)
						)
						(arc
							(start 0.2794 -0.1778)
							(mid 0.249642 -0.249642)
							(end 0.1778 -0.2794)
						)
					)
					(width 0)
					(fill yes)
				)
			)
		)
	)
)
